(kicad_pcb
	(version 20260206)
	(generator "pcbnew")
	(generator_version "10.0")
	(general
		(thickness 1.6)
		(legacy_teardrops no)
	)
	(paper "A4")
	(title_block
		(title "Bryce Canyon_F.DPB_16315-1-OCP.brd")
		(comment 1 "Bryce Canyon / footprints 121-126 of 2223")
	)
	(layers
		(0 "F.Cu" signal "TOP")
		(4 "In1.Cu" signal "L2GND")
		(6 "In2.Cu" signal "L3")
		(8 "In3.Cu" signal "L4GND")
		(10 "In4.Cu" signal "L5")
		(12 "In5.Cu" signal "L6VCC")
		(14 "In6.Cu" signal "L7VCC")
		(16 "In7.Cu" signal "L8")
		(18 "In8.Cu" signal "L9GND")
		(20 "In9.Cu" signal "L10")
		(22 "In10.Cu" signal "L11GND")
		(2 "B.Cu" signal "BOTTOM")
		(9 "F.Adhes" user "F.Adhesive")
		(11 "B.Adhes" user "B.Adhesive")
		(13 "F.Paste" user "Package Geometry/Pastemask Top")
		(15 "B.Paste" user "Package Geometry/Pastemask Bottom")
		(5 "F.SilkS" user "Ref Des/Silkscreen Top")
		(7 "B.SilkS" user "Ref Des/Silkscreen Bottom")
		(1 "F.Mask" user "Board Geometry/Soldermask Top")
		(3 "B.Mask" user "Board Geometry/Soldermask Bottom")
		(17 "Dwgs.User" user "User.Drawings")
		(19 "Cmts.User" user "User.Comments")
		(21 "Eco1.User" user "User.Eco1")
		(23 "Eco2.User" user "User.Eco2")
		(25 "Edge.Cuts" user "Board Geometry/Outline")
		(27 "Margin" user)
		(31 "F.CrtYd" user "Package Geometry/Place Bound Top")
		(29 "B.CrtYd" user "Package Geometry/Place Bound Bottom")
		(35 "F.Fab" user "Ref Des/Assembly Top")
		(33 "B.Fab" user "Ref Des/Assembly Bottom")
	)
	(footprint ""
		(layer "F.Cu")
		(at 178.435 -55.285894 180)
		(property "Reference" "Q174"
			(at 0 0 180)
			(layer "F.SilkS")
			(hide yes)
			(effects
				(font
					(size 1.27 1.27)
				)
			)
		)
		(property "Value" "AO4406AL-GP"
			(at -3.707384 -1.5367 180)
			(unlocked yes)
			(layer "F.Fab")
			(hide yes)
			(effects
				(font
					(size 1.016 1.016)
					(thickness 0.1524)
				)
			)
		)
		(property "Device Type" "SOIC8H69"
			(at -3.707384 -3.0607 180)
			(unlocked yes)
			(layer "F.Fab")
			(hide yes)
			(effects
				(font
					(size 1.016 1.016)
					(thickness 0.1524)
				)
			)
		)
		(duplicate_pad_numbers_are_jumpers no)
		(fp_line
			(start 2.1336 1.4224)
			(end 2.1336 -1.4224)
			(stroke
				(width 0.1524)
				(type default)
			)
			(layer "F.SilkS")
		)
		(fp_line
			(start 2.1336 -1.4224)
			(end -2.7432 -1.4224)
			(stroke
				(width 0.1524)
				(type default)
			)
			(layer "F.SilkS")
		)
		(fp_line
			(start -2.1844 -0.0508)
			(end -2.7178 0.508)
			(stroke
				(width 0.1524)
				(type default)
			)
			(layer "F.SilkS")
		)
		(fp_line
			(start -2.6289 3.4417)
			(end -2.6289 1.4732)
			(stroke
				(width 0.381)
				(type default)
			)
			(layer "F.SilkS")
		)
		(fp_line
			(start -2.7178 -0.508)
			(end -2.1844 -0.0508)
			(stroke
				(width 0.1524)
				(type default)
			)
			(layer "F.SilkS")
		)
		(fp_line
			(start -2.7432 1.4224)
			(end 2.1336 1.4224)
			(stroke
				(width 0.1524)
				(type default)
			)
			(layer "F.SilkS")
		)
		(fp_line
			(start -2.7432 1.4224)
			(end -2.6416 1.4224)
			(stroke
				(width 0.1524)
				(type default)
			)
			(layer "F.SilkS")
		)
		(fp_line
			(start -2.7432 -1.4224)
			(end -2.7432 1.4224)
			(stroke
				(width 0.1524)
				(type default)
			)
			(layer "F.SilkS")
		)
		(fp_poly
			(pts
				(xy -2.2098 -1.4224) (xy -2.2098 1.4224) (xy 2.2098 1.4224) (xy 2.2098 -1.4224)
			)
			(stroke
				(width 0)
				(type default)
			)
			(fill yes)
			(layer "F.SilkS")
		)
		(fp_rect
			(start -2.450084 2.999994)
			(end 2.450084 -2.999994)
			(stroke
				(width 0)
				(type default)
			)
			(fill no)
			(layer "F.CrtYd")
		)
		(fp_poly
			(pts
				(xy -2.8194 3.6322) (xy -2.8194 -3.6322) (xy 2.8194 -3.6322) (xy 2.8194 1.18364) (xy 2.450084 1.18364)
				(xy 2.450084 -2.999994) (xy -2.450084 -2.999994) (xy -2.450084 2.999994) (xy 2.450084 2.999994)
				(xy 2.450084 1.18618) (xy 2.8194 1.18618) (xy 2.8194 3.6322)
			)
			(stroke
				(width 0)
				(type default)
			)
			(fill no)
			(layer "F.CrtYd")
		)
		(fp_rect
			(start -2.8194 3.6322)
			(end 2.8194 -3.6322)
			(stroke
				(width 0)
				(type default)
			)
			(fill no)
			(layer "F.Fab")
		)
		(pad "1" smd rect
			(at -1.905 2.54 180)
			(size 0.635 1.651)
			(layers "F.Cu" "F.Mask" "F.Paste")
			(net "P5V_HDD29")
		)
		(pad "2" smd rect
			(at -0.635 2.54 180)
			(size 0.635 1.651)
			(layers "F.Cu" "F.Mask" "F.Paste")
			(net "P5V_HDD29")
		)
		(pad "3" smd rect
			(at 0.635 2.54 180)
			(size 0.635 1.651)
			(layers "F.Cu" "F.Mask" "F.Paste")
			(net "P5V_HDD29")
		)
		(pad "4" smd rect
			(at 1.905 2.54 180)
			(size 0.635 1.651)
			(layers "F.Cu" "F.Mask" "F.Paste")
			(net "SW_HDD_P29")
		)
		(pad "5" smd rect
			(at 1.905 -2.54 180)
			(size 0.635 1.651)
			(layers "F.Cu" "F.Mask" "F.Paste")
			(net "P5V_A_2")
		)
		(pad "6" smd rect
			(at 0.635 -2.54 180)
			(size 0.635 1.651)
			(layers "F.Cu" "F.Mask" "F.Paste")
			(net "P5V_A_2")
		)
		(pad "7" smd rect
			(at -0.635 -2.54 180)
			(size 0.635 1.651)
			(layers "F.Cu" "F.Mask" "F.Paste")
			(net "P5V_A_2")
		)
		(pad "8" smd rect
			(at -1.905 -2.54 180)
			(size 0.635 1.651)
			(layers "F.Cu" "F.Mask" "F.Paste")
			(net "P5V_A_2")
		)
	)
	(footprint ""
		(layer "F.Cu")
		(at 130.447796 -61.127894 90)
		(property "Reference" "C396"
			(at 0 0 90)
			(layer "F.SilkS")
			(hide yes)
			(effects
				(font
					(size 1.27 1.27)
				)
			)
		)
		(property "Value" "SCD01U50V2KX-1GP"
			(at 1.1811 -2.7051 90)
			(unlocked yes)
			(layer "F.Fab")
			(hide yes)
			(effects
				(font
					(size 1.016 1.016)
					(thickness 0.1524)
				)
			)
		)
		(property "Device Type" "C402H22"
			(at 1.1811 -4.2291 90)
			(unlocked yes)
			(layer "F.Fab")
			(hide yes)
			(effects
				(font
					(size 1.016 1.016)
					(thickness 0.1524)
				)
			)
		)
		(duplicate_pad_numbers_are_jumpers no)
		(fp_rect
			(start -0.4318 0.9525)
			(end 0.4318 -0.9525)
			(stroke
				(width 0)
				(type default)
			)
			(fill no)
			(layer "F.CrtYd")
		)
		(fp_rect
			(start -0.4318 0.9525)
			(end 0.4318 -0.9525)
			(stroke
				(width 0)
				(type default)
			)
			(fill no)
			(layer "F.Fab")
		)
		(pad "1" smd custom
			(at 0 -0.4445 90)
			(size 0.1524 0.1524)
			(layers "F.Cu" "F.Mask" "F.Paste")
			(net "HDD_PRSNT_27")
			(options
				(clearance outline)
				(anchor circle)
			)
			(primitives
				(gr_poly
					(pts
						(arc
							(start 0.3048 -0.2032)
							(mid 0.275042 -0.275042)
							(end 0.2032 -0.3048)
						)
						(arc
							(start -0.2032 -0.3048)
							(mid -0.275042 -0.275042)
							(end -0.3048 -0.2032)
						)
						(arc
							(start -0.3048 0.2032)
							(mid -0.275042 0.275042)
							(end -0.2032 0.3048)
						)
						(arc
							(start 0.2032 0.3048)
							(mid 0.275042 0.275042)
							(end 0.3048 0.2032)
						)
					)
					(width 0)
					(fill yes)
				)
			)
		)
		(pad "2" smd custom
			(at 0 0.4445 90)
			(size 0.1524 0.1524)
			(layers "F.Cu" "F.Mask" "F.Paste")
			(net "GND")
			(options
				(clearance outline)
				(anchor circle)
			)
			(primitives
				(gr_poly
					(pts
						(arc
							(start 0.3048 -0.2032)
							(mid 0.275042 -0.275042)
							(end 0.2032 -0.3048)
						)
						(arc
							(start -0.2032 -0.3048)
							(mid -0.275042 -0.275042)
							(end -0.3048 -0.2032)
						)
						(arc
							(start -0.3048 0.2032)
							(mid -0.275042 0.275042)
							(end -0.2032 0.3048)
						)
						(arc
							(start 0.2032 0.3048)
							(mid 0.275042 0.275042)
							(end 0.3048 0.2032)
						)
					)
					(width 0)
					(fill yes)
				)
			)
		)
	)
	(footprint ""
		(layer "F.Cu")
		(at 101.190044 -303.904396)
		(property "Reference" "Q254"
			(at 0 0 0)
			(layer "F.SilkS")
			(hide yes)
			(effects
				(font
					(size 1.27 1.27)
				)
			)
		)
		(property "Value" "2N7002K-2-GP"
			(at 0.127 -8.9662 0)
			(unlocked yes)
			(layer "F.Fab")
			(hide yes)
			(effects
				(font
					(size 1.016 1.016)
					(thickness 0.1524)
				)
			)
		)
		(property "Device Type" "SOT23DGS2D4H44"
			(at 0.127 -10.4902 0)
			(unlocked yes)
			(layer "F.Fab")
			(hide yes)
			(effects
				(font
					(size 1.016 1.016)
					(thickness 0.1524)
				)
			)
		)
		(duplicate_pad_numbers_are_jumpers no)
		(fp_line
			(start -1.651 -1.778)
			(end -1.651 1.778)
			(stroke
				(width 0.1524)
				(type default)
			)
			(layer "F.SilkS")
		)
		(fp_line
			(start -1.651 1.778)
			(end 1.651 1.778)
			(stroke
				(width 0.1524)
				(type default)
			)
			(layer "F.SilkS")
		)
		(fp_line
			(start 1.651 -1.778)
			(end -1.651 -1.778)
			(stroke
				(width 0.1524)
				(type default)
			)
			(layer "F.SilkS")
		)
		(fp_line
			(start 1.651 1.778)
			(end 1.651 -1.778)
			(stroke
				(width 0.1524)
				(type default)
			)
			(layer "F.SilkS")
		)
		(fp_poly
			(pts
				(xy -1.778 1.8796) (xy -1.778 -1.8796) (xy 1.778 -1.8796) (xy 1.778 1.8796)
			)
			(stroke
				(width 0)
				(type default)
			)
			(fill no)
			(layer "F.CrtYd")
		)
		(fp_poly
			(pts
				(xy -1.778 1.8796) (xy -1.778 -1.8796) (xy 1.778 -1.8796) (xy 1.778 1.8796)
			)
			(stroke
				(width 0)
				(type default)
			)
			(fill no)
			(layer "F.Fab")
		)
		(pad "D" smd custom
			(at 0 -0.9525)
			(size 0.1905 0.1905)
			(layers "F.Cu" "F.Mask" "F.Paste")
			(net "FLT_HDD27_N")
			(options
				(clearance outline)
				(anchor circle)
			)
			(primitives
				(gr_poly
					(pts
						(arc
							(start -0.1778 0.5715)
							(mid -0.321484 0.511984)
							(end -0.381 0.3683)
						)
						(arc
							(start -0.381 -0.3683)
							(mid -0.321484 -0.511984)
							(end -0.1778 -0.5715)
						)
						(arc
							(start 0.1778 -0.5715)
							(mid 0.321484 -0.511984)
							(end 0.381 -0.3683)
						)
						(arc
							(start 0.381 0.3683)
							(mid 0.321484 0.511984)
							(end 0.1778 0.5715)
						)
					)
					(width 0)
					(fill yes)
				)
			)
		)
		(pad "G" smd custom
			(at -0.98425 0.9525)
			(size 0.1905 0.1905)
			(layers "F.Cu" "F.Mask" "F.Paste")
			(net "DRIVE_B_27_FLT_LED")
			(options
				(clearance outline)
				(anchor circle)
			)
			(primitives
				(gr_poly
					(pts
						(arc
							(start -0.1778 0.5715)
							(mid -0.321484 0.511984)
							(end -0.381 0.3683)
						)
						(arc
							(start -0.381 -0.3683)
							(mid -0.321484 -0.511984)
							(end -0.1778 -0.5715)
						)
						(arc
							(start 0.1778 -0.5715)
							(mid 0.321484 -0.511984)
							(end 0.381 -0.3683)
						)
						(arc
							(start 0.381 0.3683)
							(mid 0.321484 0.511984)
							(end 0.1778 0.5715)
						)
					)
					(width 0)
					(fill yes)
				)
			)
		)
		(pad "S" smd custom
			(at 0.98425 0.9525)
			(size 0.1905 0.1905)
			(layers "F.Cu" "F.Mask" "F.Paste")
			(net "GND")
			(options
				(clearance outline)
				(anchor circle)
			)
			(primitives
				(gr_poly
					(pts
						(arc
							(start -0.1778 0.5715)
							(mid -0.321484 0.511984)
							(end -0.381 0.3683)
						)
						(arc
							(start -0.381 -0.3683)
							(mid -0.321484 -0.511984)
							(end -0.1778 -0.5715)
						)
						(arc
							(start 0.1778 -0.5715)
							(mid 0.321484 -0.511984)
							(end 0.381 -0.3683)
						)
						(arc
							(start 0.381 0.3683)
							(mid 0.321484 0.511984)
							(end 0.1778 0.5715)
						)
					)
					(width 0)
					(fill yes)
				)
			)
		)
	)
	(footprint ""
		(layer "F.Cu")
		(at 14.842998 -289.857942)
		(property "Reference" "Q218"
			(at 0 0 0)
			(layer "F.SilkS")
			(hide yes)
			(effects
				(font
					(size 1.27 1.27)
				)
			)
		)
		(property "Value" "AO4407AL-GP"
			(at -3.707384 -1.5367 0)
			(unlocked yes)
			(layer "F.Fab")
			(hide yes)
			(effects
				(font
					(size 1.016 1.016)
					(thickness 0.1524)
				)
			)
		)
		(property "Device Type" "SOIC8H69"
			(at -3.707384 -3.0607 0)
			(unlocked yes)
			(layer "F.Fab")
			(hide yes)
			(effects
				(font
					(size 1.016 1.016)
					(thickness 0.1524)
				)
			)
		)
		(duplicate_pad_numbers_are_jumpers no)
		(fp_line
			(start -2.7432 -1.4224)
			(end -2.7432 1.4224)
			(stroke
				(width 0.1524)
				(type default)
			)
			(layer "F.SilkS")
		)
		(fp_line
			(start -2.7432 1.4224)
			(end -2.6416 1.4224)
			(stroke
				(width 0.1524)
				(type default)
			)
			(layer "F.SilkS")
		)
		(fp_line
			(start -2.7432 1.4224)
			(end 2.1336 1.4224)
			(stroke
				(width 0.1524)
				(type default)
			)
			(layer "F.SilkS")
		)
		(fp_line
			(start -2.7178 -0.508)
			(end -2.1844 -0.0508)
			(stroke
				(width 0.1524)
				(type default)
			)
			(layer "F.SilkS")
		)
		(fp_line
			(start -2.6289 3.4417)
			(end -2.6289 1.4732)
			(stroke
				(width 0.381)
				(type default)
			)
			(layer "F.SilkS")
		)
		(fp_line
			(start -2.1844 -0.0508)
			(end -2.7178 0.508)
			(stroke
				(width 0.1524)
				(type default)
			)
			(layer "F.SilkS")
		)
		(fp_line
			(start 2.1336 -1.4224)
			(end -2.7432 -1.4224)
			(stroke
				(width 0.1524)
				(type default)
			)
			(layer "F.SilkS")
		)
		(fp_line
			(start 2.1336 1.4224)
			(end 2.1336 -1.4224)
			(stroke
				(width 0.1524)
				(type default)
			)
			(layer "F.SilkS")
		)
		(fp_poly
			(pts
				(xy -2.2098 -1.4224) (xy -2.2098 1.4224) (xy 2.2098 1.4224) (xy 2.2098 -1.4224)
			)
			(stroke
				(width 0)
				(type default)
			)
			(fill yes)
			(layer "F.SilkS")
		)
		(fp_rect
			(start -2.450084 2.999994)
			(end 2.450084 -2.999994)
			(stroke
				(width 0)
				(type default)
			)
			(fill no)
			(layer "F.CrtYd")
		)
		(fp_poly
			(pts
				(xy -2.8194 3.6322) (xy -2.8194 -3.6322) (xy 2.8194 -3.6322) (xy 2.8194 1.18364) (xy 2.450084 1.18364)
				(xy 2.450084 -2.999994) (xy -2.450084 -2.999994) (xy -2.450084 2.999994) (xy 2.450084 2.999994)
				(xy 2.450084 1.18618) (xy 2.8194 1.18618) (xy 2.8194 3.6322)
			)
			(stroke
				(width 0)
				(type default)
			)
			(fill no)
			(layer "F.CrtYd")
		)
		(fp_rect
			(start -2.8194 3.6322)
			(end 2.8194 -3.6322)
			(stroke
				(width 0)
				(type default)
			)
			(fill no)
			(layer "F.Fab")
		)
		(pad "1" smd rect
			(at -1.905 2.54)
			(size 0.635 1.651)
			(layers "F.Cu" "F.Mask" "F.Paste")
			(net "P12V_A")
		)
		(pad "2" smd rect
			(at -0.635 2.54)
			(size 0.635 1.651)
			(layers "F.Cu" "F.Mask" "F.Paste")
			(net "P12V_A")
		)
		(pad "3" smd rect
			(at 0.635 2.54)
			(size 0.635 1.651)
			(layers "F.Cu" "F.Mask" "F.Paste")
			(net "P12V_A")
		)
		(pad "4" smd rect
			(at 1.905 2.54)
			(size 0.635 1.651)
			(layers "F.Cu" "F.Mask" "F.Paste")
			(net "SW_HDD_N0")
		)
		(pad "5" smd rect
			(at 1.905 -2.54)
			(size 0.635 1.651)
			(layers "F.Cu" "F.Mask" "F.Paste")
			(net "P12V_HDD0")
		)
		(pad "6" smd rect
			(at 0.635 -2.54)
			(size 0.635 1.651)
			(layers "F.Cu" "F.Mask" "F.Paste")
			(net "P12V_HDD0")
		)
		(pad "7" smd rect
			(at -0.635 -2.54)
			(size 0.635 1.651)
			(layers "F.Cu" "F.Mask" "F.Paste")
			(net "P12V_HDD0")
		)
		(pad "8" smd rect
			(at -1.905 -2.54)
			(size 0.635 1.651)
			(layers "F.Cu" "F.Mask" "F.Paste")
			(net "P12V_HDD0")
		)
	)
	(footprint ""
		(layer "F.Cu")
		(at 367.338102 -272.585942 180)
		(property "Reference" "R302"
			(at 0 0 180)
			(layer "F.SilkS")
			(hide yes)
			(effects
				(font
					(size 1.27 1.27)
				)
			)
		)
		(property "Value" "0R2J-2-GP"
			(at 0.064008 -3.993896 180)
			(unlocked yes)
			(layer "F.Fab")
			(hide yes)
			(effects
				(font
					(size 1.016 1.016)
					(thickness 0.1524)
				)
			)
		)
		(property "Device Type" "R402H16"
			(at 0.064008 -5.517896 180)
			(unlocked yes)
			(layer "F.Fab")
			(hide yes)
			(effects
				(font
					(size 1.016 1.016)
					(thickness 0.1524)
				)
			)
		)
		(duplicate_pad_numbers_are_jumpers no)
		(fp_line
			(start 0.508 -0.9398)
			(end -0.508 -0.9398)
			(stroke
				(width 0.1524)
				(type default)
			)
			(layer "F.SilkS")
		)
		(fp_line
			(start -0.508 -0.9398)
			(end -0.508 0.9398)
			(stroke
				(width 0.1524)
				(type default)
			)
			(layer "F.SilkS")
		)
		(fp_rect
			(start -0.508 0.9398)
			(end 0.508 -0.9398)
			(stroke
				(width 0)
				(type default)
			)
			(fill no)
			(layer "F.CrtYd")
		)
		(fp_rect
			(start -0.508 0.9398)
			(end 0.508 -0.9398)
			(stroke
				(width 0)
				(type default)
			)
			(fill no)
			(layer "F.Fab")
		)
		(pad "1" smd custom
			(at 0 -0.4445 180)
			(size 0.1397 0.1397)
			(layers "F.Cu" "F.Mask" "F.Paste")
			(net "DRIVE_A_7_PWR")
			(options
				(clearance outline)
				(anchor circle)
			)
			(primitives
				(gr_poly
					(pts
						(arc
							(start -0.1778 -0.2794)
							(mid -0.249642 -0.249642)
							(end -0.2794 -0.1778)
						)
						(arc
							(start -0.2794 0.1778)
							(mid -0.249642 0.249642)
							(end -0.1778 0.2794)
						)
						(arc
							(start 0.1778 0.2794)
							(mid 0.249642 0.249642)
							(end 0.2794 0.1778)
						)
						(arc
							(start 0.2794 -0.1778)
							(mid 0.249642 -0.249642)
							(end 0.1778 -0.2794)
						)
					)
					(width 0)
					(fill yes)
				)
			)
		)
		(pad "2" smd custom
			(at 0 0.4445 180)
			(size 0.1397 0.1397)
			(layers "F.Cu" "F.Mask" "F.Paste")
			(net "SW_PWR_R_HDD7")
			(options
				(clearance outline)
				(anchor circle)
			)
			(primitives
				(gr_poly
					(pts
						(arc
							(start -0.1778 -0.2794)
							(mid -0.249642 -0.249642)
							(end -0.2794 -0.1778)
						)
						(arc
							(start -0.2794 0.1778)
							(mid -0.249642 0.249642)
							(end -0.1778 0.2794)
						)
						(arc
							(start 0.1778 0.2794)
							(mid 0.249642 0.249642)
							(end 0.2794 0.1778)
						)
						(arc
							(start 0.2794 -0.1778)
							(mid 0.249642 -0.249642)
							(end 0.1778 -0.2794)
						)
					)
					(width 0)
					(fill yes)
				)
			)
		)
	)
	(footprint ""
		(layer "F.Cu")
		(at 476.672148 -269.348204 180)
		(property "Reference" "R391"
			(at 0 0 180)
			(layer "F.SilkS")
			(hide yes)
			(effects
				(font
					(size 1.27 1.27)
				)
			)
		)
		(property "Value" "1KR2F-3-GP"
			(at 0.064008 -3.993896 180)
			(unlocked yes)
			(layer "F.Fab")
			(hide yes)
			(effects
				(font
					(size 1.016 1.016)
					(thickness 0.1524)
				)
			)
		)
		(property "Device Type" "R402H16"
			(at 0.064008 -5.517896 180)
			(unlocked yes)
			(layer "F.Fab")
			(hide yes)
			(effects
				(font
					(size 1.016 1.016)
					(thickness 0.1524)
				)
			)
		)
		(duplicate_pad_numbers_are_jumpers no)
		(fp_line
			(start 0.508 -0.9398)
			(end -0.508 -0.9398)
			(stroke
				(width 0.1524)
				(type default)
			)
			(layer "F.SilkS")
		)
		(fp_line
			(start -0.508 -0.9398)
			(end -0.508 0.9398)
			(stroke
				(width 0.1524)
				(type default)
			)
			(layer "F.SilkS")
		)
		(fp_rect
			(start -0.508 0.9398)
			(end 0.508 -0.9398)
			(stroke
				(width 0)
				(type default)
			)
			(fill no)
			(layer "F.CrtYd")
		)
		(fp_rect
			(start -0.508 0.9398)
			(end 0.508 -0.9398)
			(stroke
				(width 0)
				(type default)
			)
			(fill no)
			(layer "F.Fab")
		)
		(pad "1" smd custom
			(at 0 -0.4445 180)
			(size 0.1397 0.1397)
			(layers "F.Cu" "F.Mask" "F.Paste")
			(net "P3V3_STBY_A")
			(options
				(clearance outline)
				(anchor circle)
			)
			(primitives
				(gr_poly
					(pts
						(arc
							(start -0.1778 -0.2794)
							(mid -0.249642 -0.249642)
							(end -0.2794 -0.1778)
						)
						(arc
							(start -0.2794 0.1778)
							(mid -0.249642 0.249642)
							(end -0.1778 0.2794)
						)
						(arc
							(start 0.1778 0.2794)
							(mid 0.249642 0.249642)
							(end 0.2794 0.1778)
						)
						(arc
							(start 0.2794 -0.1778)
							(mid 0.249642 -0.249642)
							(end 0.1778 -0.2794)
						)
					)
					(width 0)
					(fill yes)
				)
			)
		)
		(pad "2" smd custom
			(at 0 0.4445 180)
			(size 0.1397 0.1397)
			(layers "F.Cu" "F.Mask" "F.Paste")
			(net "SW_PWR_R_HDD11")
			(options
				(clearance outline)
				(anchor circle)
			)
			(primitives
				(gr_poly
					(pts
						(arc
							(start -0.1778 -0.2794)
							(mid -0.249642 -0.249642)
							(end -0.2794 -0.1778)
						)
						(arc
							(start -0.2794 0.1778)
							(mid -0.249642 0.249642)
							(end -0.1778 0.2794)
						)
						(arc
							(start 0.1778 0.2794)
							(mid 0.249642 0.249642)
							(end 0.2794 0.1778)
						)
						(arc
							(start 0.2794 -0.1778)
							(mid 0.249642 -0.249642)
							(end 0.1778 -0.2794)
						)
					)
					(width 0)
					(fill yes)
				)
			)
		)
	)
)
